# T6G (Grand Teton) — schematic netlist excerpt (pin names and nets, part order shuffled) for the footprints in the layout excerpt that follows; sources: Cadence DE-HDL packaged netlist, KiCad conversion of 04192023_DAF0TMB3IC0_F0TG_MB_C_brd_V02_OCP.brd

R6323  Q_RES  0 5% CHIP  pkg 0402LF  page 178 : A = USB_HUB2_TI_TEST ; B = USB_HUB2_TI_TEST_MRP_PROG_FUNC6
R9012  Q_RES  0 5% CHIP  pkg 0402LF  page 245 : A = PRSNT_CABLE_SWB_B2_ISO_N ; B = PRSNT_CABLE_SWB_B2_ISO_R_N

(kicad_pcb
	(version 20260206)
	(generator "pcbnew")
	(generator_version "10.0")
	(general
		(thickness 1.6)
		(legacy_teardrops no)
	)
	(paper "A4")
	(title_block
		(title "04192023_DAF0TMB3IC0_F0TG_MB_C_brd_V02_OCP.brd")
		(comment 1 "Grand Teton / footprints 3748-3749 of 8354")
	)
	(layers
		(0 "F.Cu" signal "TOP")
		(4 "In1.Cu" signal "GND")
		(6 "In2.Cu" signal "IN1")
		(8 "In3.Cu" signal "GND1")
		(10 "In4.Cu" signal "IN2")
		(12 "In5.Cu" signal "GND2")
		(14 "In6.Cu" signal "IN3")
		(16 "In7.Cu" signal "GND3")
		(18 "In8.Cu" signal "VCC")
		(20 "In9.Cu" signal "VCC1")
		(22 "In10.Cu" signal "GND4")
		(24 "In11.Cu" signal "IN4")
		(26 "In12.Cu" signal "GND5")
		(28 "In13.Cu" signal "IN5")
		(30 "In14.Cu" signal "GND6")
		(32 "In15.Cu" signal "IN6")
		(34 "In16.Cu" signal "GND7")
		(2 "B.Cu" signal "BOTTOM")
		(9 "F.Adhes" user "F.Adhesive")
		(11 "B.Adhes" user "B.Adhesive")
		(13 "F.Paste" user "Package Geometry/Pastemask Top")
		(15 "B.Paste" user "Package Geometry/Pastemask Bottom")
		(5 "F.SilkS" user "Ref Des/Silkscreen Top")
		(7 "B.SilkS" user "Ref Des/Silkscreen Bottom")
		(1 "F.Mask" user "Board Geometry/Soldermask Top")
		(3 "B.Mask" user "Board Geometry/Soldermask Bottom")
		(17 "Dwgs.User" user "User.Drawings")
		(19 "Cmts.User" user "User.Comments")
		(21 "Eco1.User" user "User.Eco1")
		(23 "Eco2.User" user "User.Eco2")
		(25 "Edge.Cuts" user "Board Geometry/Outline")
		(27 "Margin" user)
		(31 "F.CrtYd" user "Package Geometry/Place Bound Top")
		(29 "B.CrtYd" user "Package Geometry/Place Bound Bottom")
		(35 "F.Fab" user "Ref Des/Assembly Top")
		(33 "B.Fab" user "Ref Des/Assembly Bottom")
	)
	(footprint ""
		(layer "F.Cu")
		(at 188.143642 -413.64408 90)
		(property "Reference" "R9012"
			(at 0 0 90)
			(layer "F.SilkS")
			(hide yes)
			(effects
				(font
					(size 1.27 1.27)
				)
			)
		)
		(property "Value" ""
			(at 0 0 90)
			(layer "F.Fab")
			(effects
				(font
					(size 1.27 1.27)
				)
			)
		)
		(duplicate_pad_numbers_are_jumpers no)
		(fp_line
			(start 0.7874 -0.4064)
			(end 0.7874 0.4064)
			(stroke
				(width 0.1524)
				(type default)
			)
			(layer "F.SilkS")
		)
		(fp_line
			(start -0.7874 -0.4064)
			(end 0.7874 -0.4064)
			(stroke
				(width 0.1524)
				(type default)
			)
			(layer "F.SilkS")
		)
		(fp_line
			(start 0.7874 0.4064)
			(end -0.7874 0.4064)
			(stroke
				(width 0.1524)
				(type default)
			)
			(layer "F.SilkS")
		)
		(fp_line
			(start -0.7874 0.4064)
			(end -0.7874 -0.4064)
			(stroke
				(width 0.1524)
				(type default)
			)
			(layer "F.SilkS")
		)
		(fp_line
			(start -0.12065 -0.305054)
			(end -0.12065 -0.2794)
			(stroke
				(width 0.1)
				(type default)
			)
			(layer "F.Fab")
		)
		(fp_line
			(start -0.67945 -0.305054)
			(end -0.12065 -0.305054)
			(stroke
				(width 0.1)
				(type default)
			)
			(layer "F.Fab")
		)
		(fp_line
			(start 0.67945 -0.3048)
			(end 0.67945 0.3048)
			(stroke
				(width 0.1)
				(type default)
			)
			(layer "F.Fab")
		)
		(fp_line
			(start 0.12065 -0.3048)
			(end 0.67945 -0.3048)
			(stroke
				(width 0.1)
				(type default)
			)
			(layer "F.Fab")
		)
		(fp_line
			(start 0.12065 -0.2794)
			(end 0.12065 -0.3048)
			(stroke
				(width 0.1)
				(type default)
			)
			(layer "F.Fab")
		)
		(fp_line
			(start -0.12065 -0.2794)
			(end 0.12065 -0.2794)
			(stroke
				(width 0.1)
				(type default)
			)
			(layer "F.Fab")
		)
		(fp_line
			(start 0.120396 0.2794)
			(end -0.12065 0.2794)
			(stroke
				(width 0.1)
				(type default)
			)
			(layer "F.Fab")
		)
		(fp_line
			(start -0.12065 0.2794)
			(end -0.12065 0.3048)
			(stroke
				(width 0.1)
				(type default)
			)
			(layer "F.Fab")
		)
		(fp_line
			(start 0.67945 0.3048)
			(end 0.120396 0.3048)
			(stroke
				(width 0.1)
				(type default)
			)
			(layer "F.Fab")
		)
		(fp_line
			(start 0.120396 0.3048)
			(end 0.120396 0.2794)
			(stroke
				(width 0.1)
				(type default)
			)
			(layer "F.Fab")
		)
		(fp_line
			(start -0.12065 0.3048)
			(end -0.67945 0.3048)
			(stroke
				(width 0.1)
				(type default)
			)
			(layer "F.Fab")
		)
		(fp_line
			(start -0.67945 0.3048)
			(end -0.67945 -0.305054)
			(stroke
				(width 0.1)
				(type default)
			)
			(layer "F.Fab")
		)
		(pad "1" smd circle
			(at -0.40005 0 90)
			(size 0 0)
			(layers "F.Cu" "F.Mask" "F.Paste")
			(net "PRSNT_CABLE_SWB_B2_ISO_N")
		)
		(pad "2" smd circle
			(at 0.40005 0 90)
			(size 0 0)
			(layers "F.Cu" "F.Mask" "F.Paste")
			(net "PRSNT_CABLE_SWB_B2_ISO_R_N")
		)
	)
	(footprint ""
		(layer "F.Cu")
		(at 105.191814 -36.6522)
		(property "Reference" "R6323"
			(at 0 0 0)
			(layer "F.SilkS")
			(hide yes)
			(effects
				(font
					(size 1.27 1.27)
				)
			)
		)
		(property "Value" ""
			(at 0 0 0)
			(layer "F.Fab")
			(effects
				(font
					(size 1.27 1.27)
				)
			)
		)
		(duplicate_pad_numbers_are_jumpers no)
		(fp_line
			(start -0.7874 -0.4064)
			(end 0.7874 -0.4064)
			(stroke
				(width 0.1524)
				(type default)
			)
			(layer "F.SilkS")
		)
		(fp_line
			(start -0.7874 0.4064)
			(end -0.7874 -0.4064)
			(stroke
				(width 0.1524)
				(type default)
			)
			(layer "F.SilkS")
		)
		(fp_line
			(start 0.7874 -0.4064)
			(end 0.7874 0.4064)
			(stroke
				(width 0.1524)
				(type default)
			)
			(layer "F.SilkS")
		)
		(fp_line
			(start 0.7874 0.4064)
			(end -0.7874 0.4064)
			(stroke
				(width 0.1524)
				(type default)
			)
			(layer "F.SilkS")
		)
		(fp_line
			(start -0.67945 -0.305054)
			(end -0.12065 -0.305054)
			(stroke
				(width 0.1)
				(type default)
			)
			(layer "F.Fab")
		)
		(fp_line
			(start -0.67945 0.3048)
			(end -0.67945 -0.305054)
			(stroke
				(width 0.1)
				(type default)
			)
			(layer "F.Fab")
		)
		(fp_line
			(start -0.12065 -0.305054)
			(end -0.12065 -0.2794)
			(stroke
				(width 0.1)
				(type default)
			)
			(layer "F.Fab")
		)
		(fp_line
			(start -0.12065 -0.2794)
			(end 0.12065 -0.2794)
			(stroke
				(width 0.1)
				(type default)
			)
			(layer "F.Fab")
		)
		(fp_line
			(start -0.12065 0.2794)
			(end -0.12065 0.3048)
			(stroke
				(width 0.1)
				(type default)
			)
			(layer "F.Fab")
		)
		(fp_line
			(start -0.12065 0.3048)
			(end -0.67945 0.3048)
			(stroke
				(width 0.1)
				(type default)
			)
			(layer "F.Fab")
		)
		(fp_line
			(start 0.120396 0.2794)
			(end -0.12065 0.2794)
			(stroke
				(width 0.1)
				(type default)
			)
			(layer "F.Fab")
		)
		(fp_line
			(start 0.120396 0.3048)
			(end 0.120396 0.2794)
			(stroke
				(width 0.1)
				(type default)
			)
			(layer "F.Fab")
		)
		(fp_line
			(start 0.12065 -0.3048)
			(end 0.67945 -0.3048)
			(stroke
				(width 0.1)
				(type default)
			)
			(layer "F.Fab")
		)
		(fp_line
			(start 0.12065 -0.2794)
			(end 0.12065 -0.3048)
			(stroke
				(width 0.1)
				(type default)
			)
			(layer "F.Fab")
		)
		(fp_line
			(start 0.67945 -0.3048)
			(end 0.67945 0.3048)
			(stroke
				(width 0.1)
				(type default)
			)
			(layer "F.Fab")
		)
		(fp_line
			(start 0.67945 0.3048)
			(end 0.120396 0.3048)
			(stroke
				(width 0.1)
				(type default)
			)
			(layer "F.Fab")
		)
		(pad "1" smd circle
			(at -0.40005 0)
			(size 0 0)
			(layers "F.Cu" "F.Mask" "F.Paste")
			(net "USB_HUB2_TI_TEST")
		)
		(pad "2" smd circle
			(at 0.40005 0)
			(size 0 0)
			(layers "F.Cu" "F.Mask" "F.Paste")
			(net "USB_HUB2_TI_TEST_MRP_PROG_FUNC6")
		)
	)
)
